# T6G (Grand Teton) — schematic netlist excerpt (pin names and nets, part order shuffled) for the footprints in the layout excerpt that follows; sources: Cadence DE-HDL packaged netlist, KiCad conversion of 04192023_DAF0TMB3IC0_F0TG_MB_C_brd_V02_OCP.brd

R3236  Q_RES  0 5% CHIP  pkg 0402LF  page 139 : A = RST_HP_OCP_V3_2_R_N ; B = RST_SMB_OCP_V3_2_N
PR3782  Q_RES  10 1% CHIP  pkg 0402LF  page 140 : A = P3V3_AUX ; B = P3V3_OCP_VCC_2

(kicad_pcb
	(version 20260206)
	(generator "pcbnew")
	(generator_version "10.0")
	(general
		(thickness 1.6)
		(legacy_teardrops no)
	)
	(paper "A4")
	(title_block
		(title "04192023_DAF0TMB3IC0_F0TG_MB_C_brd_V02_OCP.brd")
		(comment 1 "Grand Teton / footprints 3270-3271 of 8354")
	)
	(layers
		(0 "F.Cu" signal "TOP")
		(4 "In1.Cu" signal "GND")
		(6 "In2.Cu" signal "IN1")
		(8 "In3.Cu" signal "GND1")
		(10 "In4.Cu" signal "IN2")
		(12 "In5.Cu" signal "GND2")
		(14 "In6.Cu" signal "IN3")
		(16 "In7.Cu" signal "GND3")
		(18 "In8.Cu" signal "VCC")
		(20 "In9.Cu" signal "VCC1")
		(22 "In10.Cu" signal "GND4")
		(24 "In11.Cu" signal "IN4")
		(26 "In12.Cu" signal "GND5")
		(28 "In13.Cu" signal "IN5")
		(30 "In14.Cu" signal "GND6")
		(32 "In15.Cu" signal "IN6")
		(34 "In16.Cu" signal "GND7")
		(2 "B.Cu" signal "BOTTOM")
		(9 "F.Adhes" user "F.Adhesive")
		(11 "B.Adhes" user "B.Adhesive")
		(13 "F.Paste" user "Package Geometry/Pastemask Top")
		(15 "B.Paste" user "Package Geometry/Pastemask Bottom")
		(5 "F.SilkS" user "Ref Des/Silkscreen Top")
		(7 "B.SilkS" user "Ref Des/Silkscreen Bottom")
		(1 "F.Mask" user "Board Geometry/Soldermask Top")
		(3 "B.Mask" user "Board Geometry/Soldermask Bottom")
		(17 "Dwgs.User" user "User.Drawings")
		(19 "Cmts.User" user "User.Comments")
		(21 "Eco1.User" user "User.Eco1")
		(23 "Eco2.User" user "User.Eco2")
		(25 "Edge.Cuts" user "Board Geometry/Outline")
		(27 "Margin" user)
		(31 "F.CrtYd" user "Package Geometry/Place Bound Top")
		(29 "B.CrtYd" user "Package Geometry/Place Bound Bottom")
		(35 "F.Fab" user "Ref Des/Assembly Top")
		(33 "B.Fab" user "Ref Des/Assembly Bottom")
	)
	(footprint ""
		(layer "F.Cu")
		(at 56.50992 -30.648148)
		(property "Reference" "R3236"
			(at 0 0 0)
			(layer "F.SilkS")
			(hide yes)
			(effects
				(font
					(size 1.27 1.27)
				)
			)
		)
		(property "Value" ""
			(at 0 0 0)
			(layer "F.Fab")
			(effects
				(font
					(size 1.27 1.27)
				)
			)
		)
		(duplicate_pad_numbers_are_jumpers no)
		(fp_line
			(start -0.7874 -0.4064)
			(end 0.7874 -0.4064)
			(stroke
				(width 0.1524)
				(type default)
			)
			(layer "F.SilkS")
		)
		(fp_line
			(start -0.7874 0.4064)
			(end -0.7874 -0.4064)
			(stroke
				(width 0.1524)
				(type default)
			)
			(layer "F.SilkS")
		)
		(fp_line
			(start 0.7874 -0.4064)
			(end 0.7874 0.4064)
			(stroke
				(width 0.1524)
				(type default)
			)
			(layer "F.SilkS")
		)
		(fp_line
			(start 0.7874 0.4064)
			(end -0.7874 0.4064)
			(stroke
				(width 0.1524)
				(type default)
			)
			(layer "F.SilkS")
		)
		(fp_line
			(start -0.67945 -0.305054)
			(end -0.12065 -0.305054)
			(stroke
				(width 0.1)
				(type default)
			)
			(layer "F.Fab")
		)
		(fp_line
			(start -0.67945 0.3048)
			(end -0.67945 -0.305054)
			(stroke
				(width 0.1)
				(type default)
			)
			(layer "F.Fab")
		)
		(fp_line
			(start -0.12065 -0.305054)
			(end -0.12065 -0.2794)
			(stroke
				(width 0.1)
				(type default)
			)
			(layer "F.Fab")
		)
		(fp_line
			(start -0.12065 -0.2794)
			(end 0.12065 -0.2794)
			(stroke
				(width 0.1)
				(type default)
			)
			(layer "F.Fab")
		)
		(fp_line
			(start -0.12065 0.2794)
			(end -0.12065 0.3048)
			(stroke
				(width 0.1)
				(type default)
			)
			(layer "F.Fab")
		)
		(fp_line
			(start -0.12065 0.3048)
			(end -0.67945 0.3048)
			(stroke
				(width 0.1)
				(type default)
			)
			(layer "F.Fab")
		)
		(fp_line
			(start 0.120396 0.2794)
			(end -0.12065 0.2794)
			(stroke
				(width 0.1)
				(type default)
			)
			(layer "F.Fab")
		)
		(fp_line
			(start 0.120396 0.3048)
			(end 0.120396 0.2794)
			(stroke
				(width 0.1)
				(type default)
			)
			(layer "F.Fab")
		)
		(fp_line
			(start 0.12065 -0.3048)
			(end 0.67945 -0.3048)
			(stroke
				(width 0.1)
				(type default)
			)
			(layer "F.Fab")
		)
		(fp_line
			(start 0.12065 -0.2794)
			(end 0.12065 -0.3048)
			(stroke
				(width 0.1)
				(type default)
			)
			(layer "F.Fab")
		)
		(fp_line
			(start 0.67945 -0.3048)
			(end 0.67945 0.3048)
			(stroke
				(width 0.1)
				(type default)
			)
			(layer "F.Fab")
		)
		(fp_line
			(start 0.67945 0.3048)
			(end 0.120396 0.3048)
			(stroke
				(width 0.1)
				(type default)
			)
			(layer "F.Fab")
		)
		(pad "1" smd circle
			(at -0.40005 0)
			(size 0 0)
			(layers "F.Cu" "F.Mask" "F.Paste")
			(net "RST_HP_OCP_V3_2_R_N")
		)
		(pad "2" smd circle
			(at 0.40005 0)
			(size 0 0)
			(layers "F.Cu" "F.Mask" "F.Paste")
			(net "RST_SMB_OCP_V3_2_N")
		)
	)
	(footprint ""
		(layer "F.Cu")
		(at 93.29801 -54.701694)
		(property "Reference" "PR3782"
			(at 0 0 0)
			(layer "F.SilkS")
			(hide yes)
			(effects
				(font
					(size 1.27 1.27)
				)
			)
		)
		(property "Value" ""
			(at 0 0 0)
			(layer "F.Fab")
			(effects
				(font
					(size 1.27 1.27)
				)
			)
		)
		(duplicate_pad_numbers_are_jumpers no)
		(fp_line
			(start -0.7874 -0.4064)
			(end 0.7874 -0.4064)
			(stroke
				(width 0.1524)
				(type default)
			)
			(layer "F.SilkS")
		)
		(fp_line
			(start -0.7874 0.4064)
			(end -0.7874 -0.4064)
			(stroke
				(width 0.1524)
				(type default)
			)
			(layer "F.SilkS")
		)
		(fp_line
			(start 0.7874 -0.4064)
			(end 0.7874 0.4064)
			(stroke
				(width 0.1524)
				(type default)
			)
			(layer "F.SilkS")
		)
		(fp_line
			(start 0.7874 0.4064)
			(end -0.7874 0.4064)
			(stroke
				(width 0.1524)
				(type default)
			)
			(layer "F.SilkS")
		)
		(fp_line
			(start -0.67945 -0.305054)
			(end -0.12065 -0.305054)
			(stroke
				(width 0.1)
				(type default)
			)
			(layer "F.Fab")
		)
		(fp_line
			(start -0.67945 0.3048)
			(end -0.67945 -0.305054)
			(stroke
				(width 0.1)
				(type default)
			)
			(layer "F.Fab")
		)
		(fp_line
			(start -0.12065 -0.305054)
			(end -0.12065 -0.2794)
			(stroke
				(width 0.1)
				(type default)
			)
			(layer "F.Fab")
		)
		(fp_line
			(start -0.12065 -0.2794)
			(end 0.12065 -0.2794)
			(stroke
				(width 0.1)
				(type default)
			)
			(layer "F.Fab")
		)
		(fp_line
			(start -0.12065 0.2794)
			(end -0.12065 0.3048)
			(stroke
				(width 0.1)
				(type default)
			)
			(layer "F.Fab")
		)
		(fp_line
			(start -0.12065 0.3048)
			(end -0.67945 0.3048)
			(stroke
				(width 0.1)
				(type default)
			)
			(layer "F.Fab")
		)
		(fp_line
			(start 0.120396 0.2794)
			(end -0.12065 0.2794)
			(stroke
				(width 0.1)
				(type default)
			)
			(layer "F.Fab")
		)
		(fp_line
			(start 0.120396 0.3048)
			(end 0.120396 0.2794)
			(stroke
				(width 0.1)
				(type default)
			)
			(layer "F.Fab")
		)
		(fp_line
			(start 0.12065 -0.3048)
			(end 0.67945 -0.3048)
			(stroke
				(width 0.1)
				(type default)
			)
			(layer "F.Fab")
		)
		(fp_line
			(start 0.12065 -0.2794)
			(end 0.12065 -0.3048)
			(stroke
				(width 0.1)
				(type default)
			)
			(layer "F.Fab")
		)
		(fp_line
			(start 0.67945 -0.3048)
			(end 0.67945 0.3048)
			(stroke
				(width 0.1)
				(type default)
			)
			(layer "F.Fab")
		)
		(fp_line
			(start 0.67945 0.3048)
			(end 0.120396 0.3048)
			(stroke
				(width 0.1)
				(type default)
			)
			(layer "F.Fab")
		)
		(pad "1" smd circle
			(at -0.40005 0)
			(size 0 0)
			(layers "F.Cu" "F.Mask" "F.Paste")
			(net "P3V3_AUX")
		)
		(pad "2" smd circle
			(at 0.40005 0)
			(size 0 0)
			(layers "F.Cu" "F.Mask" "F.Paste")
			(net "P3V3_OCP_VCC_2")
		)
	)
)
